# TIMECARD (Time Appliance Project (Time Card)) — schematic netlist excerpt (pin names and nets, part order shuffled) for the footprints in the layout excerpt that follows; sources: Cadence DE-HDL packaged netlist, KiCad conversion of R4006-B0001-02_R01.brd

P1  CONN_HDR_2X10_M_S_SMT  52991-0208  pkg S_M_H_2X10_S_P0197  page 21
  \1\  = R_MAC_PPS_IN1P
  \2\  = R_MAC_USB_DP
  \3\  = R_MAC_PPS_IN1N
  \4\  = R_MAC_USB_DM
  \5\  = R_MAC_PPS_IN0P
  \6\  = XP5R0V_MAC_USB
  \7\  = R_MAC_PPS_IN0N
  \8\  = SG
  \9\  = SG
  \10\  = NC
  \11\  = NC
  \12\  = NC
  \13\  = NC
  \14\  = NC
  \15\  = SG
  \16\  = NC
  \17\  = R_MAC_PPS_OUTP
  \18\  = NC
  \19\  = R_MAC_PPS_OUTN
  \20\  = MAC_ALARM

(kicad_pcb
	(version 20260206)
	(generator "pcbnew")
	(generator_version "10.0")
	(general
		(thickness 1.6)
		(legacy_teardrops no)
	)
	(paper "A4")
	(title_block
		(title "timecard-production-celestica-r4006 — R4006-B0001-02_R01.brd")
		(comment 1 "Time Appliance Project (Time Card) / footprints 163-163 of 1113")
	)
	(layers
		(0 "F.Cu" signal "TOP")
		(4 "In1.Cu" signal "L02_GND1")
		(6 "In2.Cu" signal "L03_SIG1")
		(8 "In3.Cu" signal "L04_GND2")
		(10 "In4.Cu" signal "L05_VCC1")
		(12 "In5.Cu" signal "L06_VCC2")
		(14 "In6.Cu" signal "L07_GND3")
		(16 "In7.Cu" signal "L08_SIG2")
		(18 "In8.Cu" signal "L09_GND4")
		(2 "B.Cu" signal "BOTTOM")
		(9 "F.Adhes" user "F.Adhesive")
		(11 "B.Adhes" user "B.Adhesive")
		(13 "F.Paste" user "Package Geometry/Pastemask Top")
		(15 "B.Paste" user "Package Geometry/Pastemask Bottom")
		(5 "F.SilkS" user "Ref Des/Silkscreen Top")
		(7 "B.SilkS" user "Ref Des/Silkscreen Bottom")
		(1 "F.Mask" user "Board Geometry/Soldermask Top")
		(3 "B.Mask" user "Board Geometry/Soldermask Bottom")
		(17 "Dwgs.User" user "User.Drawings")
		(19 "Cmts.User" user "User.Comments")
		(21 "Eco1.User" user "User.Eco1")
		(23 "Eco2.User" user "User.Eco2")
		(25 "Edge.Cuts" user "Board Geometry/Outline")
		(27 "Margin" user)
		(31 "F.CrtYd" user "Package Geometry/Place Bound Top")
		(29 "B.CrtYd" user "Package Geometry/Place Bound Bottom")
		(35 "F.Fab" user "Ref Des/Assembly Top")
		(33 "B.Fab" user "Ref Des/Assembly Bottom")
	)
	(footprint ""
		(layer "F.Cu")
		(at 72.35444 -46.746668 -90)
		(property "Reference" "P1"
			(at 0.558038 -4.60756 0)
			(unlocked yes)
			(layer "F.SilkS")
			(effects
				(font
					(size 0.7874 0.5842)
					(thickness 0.1524)
				)
			)
		)
		(property "Value" ""
			(at 0 0 270)
			(layer "F.Fab")
			(effects
				(font
					(size 1.27 1.27)
				)
			)
		)
		(property "User Part Number" "PARTNUM*"
			(at 0.051054 6.007608 270)
			(unlocked yes)
			(layer "Cmts.User")
			(hide yes)
			(effects
				(font
					(size 0.7874 0.5842)
					(thickness 0.1524)
				)
			)
		)
		(property "Device Type" "CONN_HDR_2X10_M_S_SMT-G200-130A"
			(at 0.051054 4.813808 270)
			(unlocked yes)
			(layer "F.Fab")
			(hide yes)
			(effects
				(font
					(size 0.7874 0.5842)
					(thickness 0.1524)
				)
			)
		)
		(duplicate_pad_numbers_are_jumpers no)
		(fp_line
			(start -4.01828 3.155696)
			(end 4.754118 3.155696)
			(stroke
				(width 0.1)
				(type default)
			)
			(layer "F.SilkS")
		)
		(fp_line
			(start 4.754118 3.155696)
			(end 4.754118 -3.155696)
			(stroke
				(width 0.1)
				(type default)
			)
			(layer "F.SilkS")
		)
		(fp_line
			(start -4.754118 2.419858)
			(end -4.01828 3.155696)
			(stroke
				(width 0.1)
				(type default)
			)
			(layer "F.SilkS")
		)
		(fp_line
			(start -4.754118 -3.155696)
			(end -4.754118 2.419858)
			(stroke
				(width 0.1)
				(type default)
			)
			(layer "F.SilkS")
		)
		(fp_line
			(start 4.754118 -3.155696)
			(end -4.754118 -3.155696)
			(stroke
				(width 0.1)
				(type default)
			)
			(layer "F.SilkS")
		)
		(fp_poly
			(pts
				(xy -5.008118 2.525014) (xy -5.008118 -3.409696) (xy 5.008118 -3.409696) (xy 5.008118 3.409696)
				(xy -4.123436 3.409696)
			)
			(stroke
				(width 0)
				(type default)
			)
			(fill no)
			(layer "F.CrtYd")
		)
		(fp_line
			(start -4.01447 2.800096)
			(end -4.500118 2.314702)
			(stroke
				(width 0.1)
				(type default)
			)
			(layer "F.Fab")
		)
		(fp_line
			(start 4.500118 2.800096)
			(end -4.01447 2.800096)
			(stroke
				(width 0.1)
				(type default)
			)
			(layer "F.Fab")
		)
		(fp_line
			(start -4.500118 2.314702)
			(end -4.500118 -2.800096)
			(stroke
				(width 0.1)
				(type default)
			)
			(layer "F.Fab")
		)
		(fp_line
			(start -4.500118 -2.800096)
			(end 4.500118 -2.800096)
			(stroke
				(width 0.1)
				(type default)
			)
			(layer "F.Fab")
		)
		(fp_line
			(start 4.500118 -2.800096)
			(end 4.500118 2.800096)
			(stroke
				(width 0.1)
				(type default)
			)
			(layer "F.Fab")
		)
		(fp_text user "1"
			(at -2.624582 3.77444 0)
			(unlocked yes)
			(layer "F.SilkS")
			(effects
				(font
					(size 0.635 0.4064)
					(thickness 0.1524)
				)
			)
		)
		(fp_text user "19"
			(at 2.455418 3.77444 0)
			(unlocked yes)
			(layer "F.SilkS")
			(effects
				(font
					(size 0.635 0.4064)
					(thickness 0.1524)
				)
			)
		)
		(fp_text user "2"
			(at -2.624582 -3.71856 0)
			(unlocked yes)
			(layer "F.SilkS")
			(effects
				(font
					(size 0.635 0.4064)
					(thickness 0.1524)
				)
			)
		)
		(fp_text user "20"
			(at 1.693418 -4.09956 0)
			(unlocked yes)
			(layer "F.SilkS")
			(effects
				(font
					(size 0.635 0.4064)
					(thickness 0.1524)
				)
			)
		)
		(fp_text user "19"
			(at 3.085338 3.77444 0)
			(unlocked yes)
			(layer "F.Fab")
			(effects
				(font
					(size 0.7874 0.5842)
					(thickness 0.1524)
				)
			)
		)
		(fp_text user "1"
			(at -2.687066 3.14071 0)
			(unlocked yes)
			(layer "F.Fab")
			(effects
				(font
					(size 0.7874 0.5842)
					(thickness 0.1524)
				)
			)
		)
		(fp_text user "2"
			(at -1.875536 -3.850386 0)
			(unlocked yes)
			(layer "F.Fab")
			(effects
				(font
					(size 0.7874 0.5842)
					(thickness 0.1524)
				)
			)
		)
		(fp_text user "20"
			(at 2.980436 -3.89128 0)
			(unlocked yes)
			(layer "F.Fab")
			(effects
				(font
					(size 0.7874 0.5842)
					(thickness 0.1524)
				)
			)
		)
		(pad "1" smd rect
			(at -2.249932 1.999996 270)
			(size 0.254 1.8034)
			(layers "F.Cu" "F.Mask" "F.Paste")
			(net "R_MAC_PPS_IN1P")
		)
		(pad "2" smd rect
			(at -2.249932 -1.999996 270)
			(size 0.254 1.8034)
			(layers "F.Cu" "F.Mask" "F.Paste")
			(net "R_MAC_USB_DP")
		)
		(pad "3" smd rect
			(at -1.75006 1.999996 270)
			(size 0.254 1.8034)
			(layers "F.Cu" "F.Mask" "F.Paste")
			(net "R_MAC_PPS_IN1N")
		)
		(pad "4" smd rect
			(at -1.75006 -1.999996 270)
			(size 0.254 1.8034)
			(layers "F.Cu" "F.Mask" "F.Paste")
			(net "R_MAC_USB_DM")
		)
		(pad "5" smd rect
			(at -1.249934 1.999996 270)
			(size 0.254 1.8034)
			(layers "F.Cu" "F.Mask" "F.Paste")
			(net "R_MAC_PPS_IN0P")
		)
		(pad "6" smd rect
			(at -1.249934 -1.999996 270)
			(size 0.254 1.8034)
			(layers "F.Cu" "F.Mask" "F.Paste")
			(net "XP5R0V_MAC_USB")
		)
		(pad "7" smd rect
			(at -0.750062 1.999996 270)
			(size 0.254 1.8034)
			(layers "F.Cu" "F.Mask" "F.Paste")
			(net "R_MAC_PPS_IN0N")
		)
		(pad "8" smd rect
			(at -0.750062 -1.999996 270)
			(size 0.254 1.8034)
			(layers "F.Cu" "F.Mask" "F.Paste")
			(net "SG")
		)
		(pad "9" smd rect
			(at -0.249936 1.999996 270)
			(size 0.254 1.8034)
			(layers "F.Cu" "F.Mask" "F.Paste")
			(net "SG")
		)
		(pad "10" smd rect
			(at -0.249936 -1.999996 270)
			(size 0.254 1.8034)
			(layers "F.Cu" "F.Mask" "F.Paste")
			(net "Net_773")
		)
		(pad "11" smd rect
			(at 0.249936 1.999996 270)
			(size 0.254 1.8034)
			(layers "F.Cu" "F.Mask" "F.Paste")
			(net "Net_772")
		)
		(pad "12" smd rect
			(at 0.249936 -1.999996 270)
			(size 0.254 1.8034)
			(layers "F.Cu" "F.Mask" "F.Paste")
			(net "Net_771")
		)
		(pad "13" smd rect
			(at 0.750062 1.999996 270)
			(size 0.254 1.8034)
			(layers "F.Cu" "F.Mask" "F.Paste")
			(net "Net_770")
		)
		(pad "14" smd rect
			(at 0.750062 -1.999996 270)
			(size 0.254 1.8034)
			(layers "F.Cu" "F.Mask" "F.Paste")
			(net "Net_769")
		)
		(pad "15" smd rect
			(at 1.249934 1.999996 270)
			(size 0.254 1.8034)
			(layers "F.Cu" "F.Mask" "F.Paste")
			(net "SG")
		)
		(pad "16" smd rect
			(at 1.249934 -1.999996 270)
			(size 0.254 1.8034)
			(layers "F.Cu" "F.Mask" "F.Paste")
			(net "Net_768")
		)
		(pad "17" smd rect
			(at 1.75006 1.999996 270)
			(size 0.254 1.8034)
			(layers "F.Cu" "F.Mask" "F.Paste")
			(net "R_MAC_PPS_OUTP")
		)
		(pad "18" smd rect
			(at 1.75006 -1.999996 270)
			(size 0.254 1.8034)
			(layers "F.Cu" "F.Mask" "F.Paste")
			(net "Net_767")
		)
		(pad "19" smd rect
			(at 2.249932 1.999996 270)
			(size 0.254 1.8034)
			(layers "F.Cu" "F.Mask" "F.Paste")
			(net "R_MAC_PPS_OUTN")
		)
		(pad "20" smd rect
			(at 2.249932 -1.999996 270)
			(size 0.254 1.8034)
			(layers "F.Cu" "F.Mask" "F.Paste")
			(net "MAC_ALARM")
		)
	)
)
